(kicad_pcb
	(version 20260206)
	(generator "pcbnew")
	(generator_version "10.0")
	(general
		(thickness 1.6)
		(legacy_teardrops no)
	)
	(paper "A4")
	(title_block
		(title "timecard-production-celestica-r4006 — R4006-B0001-02_R01.brd")
		(comment 1 "Time Appliance Project (Time Card) / footprint 197 of 1113 (U24), pads 454-484 of 484")
	)
	(layers
		(0 "F.Cu" signal "TOP")
		(4 "In1.Cu" signal "L02_GND1")
		(6 "In2.Cu" signal "L03_SIG1")
		(8 "In3.Cu" signal "L04_GND2")
		(10 "In4.Cu" signal "L05_VCC1")
		(12 "In5.Cu" signal "L06_VCC2")
		(14 "In6.Cu" signal "L07_GND3")
		(16 "In7.Cu" signal "L08_SIG2")
		(18 "In8.Cu" signal "L09_GND4")
		(2 "B.Cu" signal "BOTTOM")
		(9 "F.Adhes" user "F.Adhesive")
		(11 "B.Adhes" user "B.Adhesive")
		(13 "F.Paste" user "Package Geometry/Pastemask Top")
		(15 "B.Paste" user "Package Geometry/Pastemask Bottom")
		(5 "F.SilkS" user "Ref Des/Silkscreen Top")
		(7 "B.SilkS" user "Ref Des/Silkscreen Bottom")
		(1 "F.Mask" user "Board Geometry/Soldermask Top")
		(3 "B.Mask" user "Board Geometry/Soldermask Bottom")
		(17 "Dwgs.User" user "User.Drawings")
		(19 "Cmts.User" user "User.Comments")
		(21 "Eco1.User" user "User.Eco1")
		(23 "Eco2.User" user "User.Eco2")
		(25 "Edge.Cuts" user "Board Geometry/Outline")
		(27 "Margin" user)
		(31 "F.CrtYd" user "Package Geometry/Place Bound Top")
		(29 "B.CrtYd" user "Package Geometry/Place Bound Bottom")
		(35 "F.Fab" user "Ref Des/Assembly Top")
		(33 "B.Fab" user "Ref Des/Assembly Bottom")
	)
	(footprint ""
		(layer "F.Cu")
		(at 109.347 -44.323 90)
		(property "Reference" "U24"
			(at 12.27963 3.683 0)
			(unlocked yes)
			(layer "F.SilkS")
			(effects
				(font
					(size 0.7874 0.5842)
					(thickness 0.1524)
				)
			)
		)
		(property "Value" ""
			(at 0 0 90)
			(layer "F.Fab")
			(effects
				(font
					(size 1.27 1.27)
				)
			)
		)
		(property "User Part Number" "PARTNUM*"
			(at 0 14.056868 90)
			(unlocked yes)
			(layer "Cmts.User")
			(hide yes)
			(effects
				(font
					(size 0.7874 0.5842)
					(thickness 0.1524)
				)
			)
		)
		(property "Device Type" "XC7A200T_2FBG484C_FBG484-G240-A"
			(at 0 12.863068 90)
			(unlocked yes)
			(layer "F.Fab")
			(hide yes)
			(effects
				(font
					(size 0.7874 0.5842)
					(thickness 0.1524)
				)
			)
		)
		(duplicate_pad_numbers_are_jumpers no)
		(pad "W14" smd circle
			(at 2.500122 7.500112 90)
			(size 0.50038 0.50038)
			(layers "F.Cu" "F.Mask" "F.Paste")
			(net "FPGA_IN_GPSTP1_OUT")
		)
		(pad "W15" smd circle
			(at 3.50012 7.500112 90)
			(size 0.50038 0.50038)
			(layers "F.Cu" "F.Mask" "F.Paste")
			(net "Net_46")
		)
		(pad "W16" smd circle
			(at 4.500118 7.500112 90)
			(size 0.50038 0.50038)
			(layers "F.Cu" "F.Mask" "F.Paste")
			(net "Net_43")
		)
		(pad "W17" smd circle
			(at 5.500116 7.500112 90)
			(size 0.50038 0.50038)
			(layers "F.Cu" "F.Mask" "F.Paste")
			(net "Net_44")
		)
		(pad "W18" smd circle
			(at 6.500114 7.500112 90)
			(size 0.50038 0.50038)
			(layers "F.Cu" "F.Mask" "F.Paste")
			(net "SG")
		)
		(pad "W19" smd circle
			(at 7.500112 7.500112 90)
			(size 0.50038 0.50038)
			(layers "F.Cu" "F.Mask" "F.Paste")
			(net "FPGA_M_RGB_LED_I2C_SDA")
		)
		(pad "W20" smd circle
			(at 8.50011 7.500112 90)
			(size 0.50038 0.50038)
			(layers "F.Cu" "F.Mask" "F.Paste")
			(net "FPGA_M_RGB_LED_I2C_SCL")
		)
		(pad "W21" smd circle
			(at 9.500108 7.500112 90)
			(size 0.50038 0.50038)
			(layers "F.Cu" "F.Mask" "F.Paste")
			(net "Net_175")
		)
		(pad "W22" smd circle
			(at 10.500106 7.500112 90)
			(size 0.50038 0.50038)
			(layers "F.Cu" "F.Mask" "F.Paste")
			(net "Net_79")
		)
		(pad "Y1" smd circle
			(at -10.500106 8.50011 90)
			(size 0.50038 0.50038)
			(layers "F.Cu" "F.Mask" "F.Paste")
			(net "FPGA_IN_MAC_PPS_OUTN")
		)
		(pad "Y2" smd circle
			(at -9.500108 8.50011 90)
			(size 0.50038 0.50038)
			(layers "F.Cu" "F.Mask" "F.Paste")
			(net "Net_136")
		)
		(pad "Y3" smd circle
			(at -8.50011 8.50011 90)
			(size 0.50038 0.50038)
			(layers "F.Cu" "F.Mask" "F.Paste")
			(net "Net_160")
		)
		(pad "Y4" smd circle
			(at -7.499858 8.50011 90)
			(size 0.50038 0.50038)
			(layers "F.Cu" "F.Mask" "F.Paste")
			(net "Net_96")
		)
		(pad "Y5" smd circle
			(at -6.49986 8.50011 90)
			(size 0.50038 0.50038)
			(layers "F.Cu" "F.Mask" "F.Paste")
			(net "SG")
		)
		(pad "Y6" smd circle
			(at -5.499862 8.50011 90)
			(size 0.50038 0.50038)
			(layers "F.Cu" "F.Mask" "F.Paste")
			(net "Net_55")
		)
		(pad "Y7" smd circle
			(at -4.499864 8.50011 90)
			(size 0.50038 0.50038)
			(layers "F.Cu" "F.Mask" "F.Paste")
			(net "IO_L23N_34")
		)
		(pad "Y8" smd circle
			(at -3.499866 8.50011 90)
			(size 0.50038 0.50038)
			(layers "F.Cu" "F.Mask" "F.Paste")
			(net "IO_L23P_34")
		)
		(pad "Y9" smd circle
			(at -2.499868 8.50011 90)
			(size 0.50038 0.50038)
			(layers "F.Cu" "F.Mask" "F.Paste")
			(net "IO_L24N_34")
		)
		(pad "Y10" smd circle
			(at -1.49987 8.50011 90)
			(size 0.50038 0.50038)
			(layers "F.Cu" "F.Mask" "F.Paste")
			(net "XP3R3V_FPGA")
		)
		(pad "Y11" smd circle
			(at -0.499872 8.50011 90)
			(size 0.50038 0.50038)
			(layers "F.Cu" "F.Mask" "F.Paste")
			(net "ANT3_IN")
		)
		(pad "Y12" smd circle
			(at 0.500126 8.50011 90)
			(size 0.50038 0.50038)
			(layers "F.Cu" "F.Mask" "F.Paste")
			(net "ANT4_IN")
		)
		(pad "Y13" smd circle
			(at 1.500124 8.50011 90)
			(size 0.50038 0.50038)
			(layers "F.Cu" "F.Mask" "F.Paste")
			(net "Net_143")
		)
		(pad "Y14" smd circle
			(at 2.500122 8.50011 90)
			(size 0.50038 0.50038)
			(layers "F.Cu" "F.Mask" "F.Paste")
			(net "FPGA_IN_GPSTP2_OUT")
		)
		(pad "Y15" smd circle
			(at 3.50012 8.50011 90)
			(size 0.50038 0.50038)
			(layers "F.Cu" "F.Mask" "F.Paste")
			(net "SG")
		)
		(pad "Y16" smd circle
			(at 4.500118 8.50011 90)
			(size 0.50038 0.50038)
			(layers "F.Cu" "F.Mask" "F.Paste")
			(net "FPGA_OUT_GPS_RST_N")
		)
		(pad "Y17" smd circle
			(at 5.500116 8.50011 90)
			(size 0.50038 0.50038)
			(layers "F.Cu" "F.Mask" "F.Paste")
			(net "Net_27")
		)
		(pad "Y18" smd circle
			(at 6.500114 8.50011 90)
			(size 0.50038 0.50038)
			(layers "F.Cu" "F.Mask" "F.Paste")
			(net "FPGA_OUT_RGB_LED_SHUTDOWN_N")
		)
		(pad "Y19" smd circle
			(at 7.500112 8.50011 90)
			(size 0.50038 0.50038)
			(layers "F.Cu" "F.Mask" "F.Paste")
			(net "Net_167")
		)
		(pad "Y20" smd circle
			(at 8.50011 8.50011 90)
			(size 0.50038 0.50038)
			(layers "F.Cu" "F.Mask" "F.Paste")
			(net "XP3R3V_FPGA")
		)
		(pad "Y21" smd circle
			(at 9.500108 8.50011 90)
			(size 0.50038 0.50038)
			(layers "F.Cu" "F.Mask" "F.Paste")
			(net "Net_84")
		)
		(pad "Y22" smd circle
			(at 10.500106 8.50011 90)
			(size 0.50038 0.50038)
			(layers "F.Cu" "F.Mask" "F.Paste")
			(net "Net_82")
		)
	)
)
